(kicad_pcb
	(version 20260206)
	(generator "pcbnew")
	(generator_version "10.0")
	(general
		(thickness 1.6)
		(legacy_teardrops no)
	)
	(paper "A4")
	(title_block
		(title "03242023_DA0F0TMBIJ0_F0T_Motherboard_J_brd_V01_OCP.brd")
		(comment 1 "Grand Teton / footprints 3262-3268 of 6105")
	)
	(layers
		(0 "F.Cu" signal "TOP")
		(4 "In1.Cu" signal "GND")
		(6 "In2.Cu" signal "IN1")
		(8 "In3.Cu" signal "GND1")
		(10 "In4.Cu" signal "IN2")
		(12 "In5.Cu" signal "GND2")
		(14 "In6.Cu" signal "IN3")
		(16 "In7.Cu" signal "GND3")
		(18 "In8.Cu" signal "VCC")
		(20 "In9.Cu" signal "VCC1")
		(22 "In10.Cu" signal "GND4")
		(24 "In11.Cu" signal "IN4")
		(26 "In12.Cu" signal "GND5")
		(28 "In13.Cu" signal "IN5")
		(30 "In14.Cu" signal "GND6")
		(32 "In15.Cu" signal "IN6")
		(34 "In16.Cu" signal "GND7")
		(2 "B.Cu" signal "BOTTOM")
		(9 "F.Adhes" user "F.Adhesive")
		(11 "B.Adhes" user "B.Adhesive")
		(13 "F.Paste" user "Package Geometry/Pastemask Top")
		(15 "B.Paste" user "Package Geometry/Pastemask Bottom")
		(5 "F.SilkS" user "Ref Des/Silkscreen Top")
		(7 "B.SilkS" user "Ref Des/Silkscreen Bottom")
		(1 "F.Mask" user "Board Geometry/Soldermask Top")
		(3 "B.Mask" user "Board Geometry/Soldermask Bottom")
		(17 "Dwgs.User" user "User.Drawings")
		(19 "Cmts.User" user "User.Comments")
		(21 "Eco1.User" user "User.Eco1")
		(23 "Eco2.User" user "User.Eco2")
		(25 "Edge.Cuts" user "Board Geometry/Outline")
		(27 "Margin" user)
		(31 "F.CrtYd" user "Package Geometry/Place Bound Top")
		(29 "B.CrtYd" user "Package Geometry/Place Bound Bottom")
		(35 "F.Fab" user "Ref Des/Assembly Top")
		(33 "B.Fab" user "Ref Des/Assembly Bottom")
	)
	(footprint ""
		(layer "F.Cu")
		(at 159.655256 -66.091308)
		(property "Reference" "R3772"
			(at 0 0 0)
			(layer "F.SilkS")
			(hide yes)
			(effects
				(font
					(size 1.27 1.27)
				)
			)
		)
		(property "Value" ""
			(at 0 0 0)
			(layer "F.Fab")
			(effects
				(font
					(size 1.27 1.27)
				)
			)
		)
		(duplicate_pad_numbers_are_jumpers no)
		(fp_line
			(start -0.7874 -0.4064)
			(end 0.7874 -0.4064)
			(stroke
				(width 0.1524)
				(type default)
			)
			(layer "F.SilkS")
		)
		(fp_line
			(start -0.7874 0.4064)
			(end -0.7874 -0.4064)
			(stroke
				(width 0.1524)
				(type default)
			)
			(layer "F.SilkS")
		)
		(fp_line
			(start 0.7874 -0.4064)
			(end 0.7874 0.4064)
			(stroke
				(width 0.1524)
				(type default)
			)
			(layer "F.SilkS")
		)
		(fp_line
			(start 0.7874 0.4064)
			(end -0.7874 0.4064)
			(stroke
				(width 0.1524)
				(type default)
			)
			(layer "F.SilkS")
		)
		(fp_line
			(start -0.67945 -0.305054)
			(end -0.12065 -0.305054)
			(stroke
				(width 0.1)
				(type default)
			)
			(layer "F.Fab")
		)
		(fp_line
			(start -0.67945 0.3048)
			(end -0.67945 -0.305054)
			(stroke
				(width 0.1)
				(type default)
			)
			(layer "F.Fab")
		)
		(fp_line
			(start -0.12065 -0.305054)
			(end -0.12065 -0.2794)
			(stroke
				(width 0.1)
				(type default)
			)
			(layer "F.Fab")
		)
		(fp_line
			(start -0.12065 -0.2794)
			(end 0.12065 -0.2794)
			(stroke
				(width 0.1)
				(type default)
			)
			(layer "F.Fab")
		)
		(fp_line
			(start -0.12065 0.2794)
			(end -0.12065 0.3048)
			(stroke
				(width 0.1)
				(type default)
			)
			(layer "F.Fab")
		)
		(fp_line
			(start -0.12065 0.3048)
			(end -0.67945 0.3048)
			(stroke
				(width 0.1)
				(type default)
			)
			(layer "F.Fab")
		)
		(fp_line
			(start 0.120396 0.2794)
			(end -0.12065 0.2794)
			(stroke
				(width 0.1)
				(type default)
			)
			(layer "F.Fab")
		)
		(fp_line
			(start 0.120396 0.3048)
			(end 0.120396 0.2794)
			(stroke
				(width 0.1)
				(type default)
			)
			(layer "F.Fab")
		)
		(fp_line
			(start 0.12065 -0.3048)
			(end 0.67945 -0.3048)
			(stroke
				(width 0.1)
				(type default)
			)
			(layer "F.Fab")
		)
		(fp_line
			(start 0.12065 -0.2794)
			(end 0.12065 -0.3048)
			(stroke
				(width 0.1)
				(type default)
			)
			(layer "F.Fab")
		)
		(fp_line
			(start 0.67945 -0.3048)
			(end 0.67945 0.3048)
			(stroke
				(width 0.1)
				(type default)
			)
			(layer "F.Fab")
		)
		(fp_line
			(start 0.67945 0.3048)
			(end 0.120396 0.3048)
			(stroke
				(width 0.1)
				(type default)
			)
			(layer "F.Fab")
		)
		(pad "1" smd circle
			(at -0.40005 0)
			(size 0 0)
			(layers "F.Cu" "F.Mask" "F.Paste")
			(net "RST_SMB_BUF_E1S_0_N")
		)
		(pad "2" smd circle
			(at 0.40005 0)
			(size 0 0)
			(layers "F.Cu" "F.Mask" "F.Paste")
			(net "RST_SMB_E1S_0_N")
		)
	)
	(footprint ""
		(layer "F.Cu")
		(at 366.48263 -249.320304 -90)
		(property "Reference" "C977"
			(at 0 0 270)
			(layer "F.SilkS")
			(hide yes)
			(effects
				(font
					(size 1.27 1.27)
				)
			)
		)
		(property "Value" ""
			(at 0 0 270)
			(layer "F.Fab")
			(effects
				(font
					(size 1.27 1.27)
				)
			)
		)
		(duplicate_pad_numbers_are_jumpers no)
		(fp_line
			(start -0.7874 0.4064)
			(end -0.7874 -0.4064)
			(stroke
				(width 0.1524)
				(type default)
			)
			(layer "F.SilkS")
		)
		(fp_line
			(start 0.7874 0.4064)
			(end -0.7874 0.4064)
			(stroke
				(width 0.1524)
				(type default)
			)
			(layer "F.SilkS")
		)
		(fp_line
			(start -0.7874 -0.4064)
			(end 0.7874 -0.4064)
			(stroke
				(width 0.1524)
				(type default)
			)
			(layer "F.SilkS")
		)
		(fp_line
			(start 0.7874 -0.4064)
			(end 0.7874 0.4064)
			(stroke
				(width 0.1524)
				(type default)
			)
			(layer "F.SilkS")
		)
		(fp_line
			(start -0.67945 0.3048)
			(end -0.67945 -0.305054)
			(stroke
				(width 0.1)
				(type default)
			)
			(layer "F.Fab")
		)
		(fp_line
			(start -0.12065 0.3048)
			(end -0.67945 0.3048)
			(stroke
				(width 0.1)
				(type default)
			)
			(layer "F.Fab")
		)
		(fp_line
			(start 0.120396 0.3048)
			(end 0.120396 0.2794)
			(stroke
				(width 0.1)
				(type default)
			)
			(layer "F.Fab")
		)
		(fp_line
			(start 0.67945 0.3048)
			(end 0.120396 0.3048)
			(stroke
				(width 0.1)
				(type default)
			)
			(layer "F.Fab")
		)
		(fp_line
			(start -0.12065 0.2794)
			(end -0.12065 0.3048)
			(stroke
				(width 0.1)
				(type default)
			)
			(layer "F.Fab")
		)
		(fp_line
			(start 0.120396 0.2794)
			(end -0.12065 0.2794)
			(stroke
				(width 0.1)
				(type default)
			)
			(layer "F.Fab")
		)
		(fp_line
			(start -0.12065 -0.2794)
			(end 0.12065 -0.2794)
			(stroke
				(width 0.1)
				(type default)
			)
			(layer "F.Fab")
		)
		(fp_line
			(start 0.12065 -0.2794)
			(end 0.12065 -0.3048)
			(stroke
				(width 0.1)
				(type default)
			)
			(layer "F.Fab")
		)
		(fp_line
			(start 0.12065 -0.3048)
			(end 0.67945 -0.3048)
			(stroke
				(width 0.1)
				(type default)
			)
			(layer "F.Fab")
		)
		(fp_line
			(start 0.67945 -0.3048)
			(end 0.67945 0.3048)
			(stroke
				(width 0.1)
				(type default)
			)
			(layer "F.Fab")
		)
		(fp_line
			(start -0.67945 -0.305054)
			(end -0.12065 -0.305054)
			(stroke
				(width 0.1)
				(type default)
			)
			(layer "F.Fab")
		)
		(fp_line
			(start -0.12065 -0.305054)
			(end -0.12065 -0.2794)
			(stroke
				(width 0.1)
				(type default)
			)
			(layer "F.Fab")
		)
		(pad "1" smd circle
			(at -0.40005 0 270)
			(size 0 0)
			(layers "F.Cu" "F.Mask" "F.Paste")
			(net "PVCCIN_CPU0")
		)
		(pad "2" smd circle
			(at 0.40005 0 270)
			(size 0 0)
			(layers "F.Cu" "F.Mask" "F.Paste")
			(net "GND")
		)
	)
	(footprint ""
		(layer "F.Cu")
		(at 49.324514 -394.44676 180)
		(property "Reference" "R4642"
			(at 0 0 180)
			(layer "F.SilkS")
			(hide yes)
			(effects
				(font
					(size 1.27 1.27)
				)
			)
		)
		(property "Value" ""
			(at 0 0 180)
			(layer "F.Fab")
			(effects
				(font
					(size 1.27 1.27)
				)
			)
		)
		(duplicate_pad_numbers_are_jumpers no)
		(fp_line
			(start 0.7874 0.4064)
			(end -0.7874 0.4064)
			(stroke
				(width 0.1524)
				(type default)
			)
			(layer "F.SilkS")
		)
		(fp_line
			(start 0.7874 -0.4064)
			(end 0.7874 0.4064)
			(stroke
				(width 0.1524)
				(type default)
			)
			(layer "F.SilkS")
		)
		(fp_line
			(start -0.7874 0.4064)
			(end -0.7874 -0.4064)
			(stroke
				(width 0.1524)
				(type default)
			)
			(layer "F.SilkS")
		)
		(fp_line
			(start -0.7874 -0.4064)
			(end 0.7874 -0.4064)
			(stroke
				(width 0.1524)
				(type default)
			)
			(layer "F.SilkS")
		)
		(fp_line
			(start 0.67945 0.3048)
			(end 0.120396 0.3048)
			(stroke
				(width 0.1)
				(type default)
			)
			(layer "F.Fab")
		)
		(fp_line
			(start 0.67945 -0.3048)
			(end 0.67945 0.3048)
			(stroke
				(width 0.1)
				(type default)
			)
			(layer "F.Fab")
		)
		(fp_line
			(start 0.12065 -0.2794)
			(end 0.12065 -0.3048)
			(stroke
				(width 0.1)
				(type default)
			)
			(layer "F.Fab")
		)
		(fp_line
			(start 0.12065 -0.3048)
			(end 0.67945 -0.3048)
			(stroke
				(width 0.1)
				(type default)
			)
			(layer "F.Fab")
		)
		(fp_line
			(start 0.120396 0.3048)
			(end 0.120396 0.2794)
			(stroke
				(width 0.1)
				(type default)
			)
			(layer "F.Fab")
		)
		(fp_line
			(start 0.120396 0.2794)
			(end -0.12065 0.2794)
			(stroke
				(width 0.1)
				(type default)
			)
			(layer "F.Fab")
		)
		(fp_line
			(start -0.12065 0.3048)
			(end -0.67945 0.3048)
			(stroke
				(width 0.1)
				(type default)
			)
			(layer "F.Fab")
		)
		(fp_line
			(start -0.12065 0.2794)
			(end -0.12065 0.3048)
			(stroke
				(width 0.1)
				(type default)
			)
			(layer "F.Fab")
		)
		(fp_line
			(start -0.12065 -0.2794)
			(end 0.12065 -0.2794)
			(stroke
				(width 0.1)
				(type default)
			)
			(layer "F.Fab")
		)
		(fp_line
			(start -0.12065 -0.305054)
			(end -0.12065 -0.2794)
			(stroke
				(width 0.1)
				(type default)
			)
			(layer "F.Fab")
		)
		(fp_line
			(start -0.67945 0.3048)
			(end -0.67945 -0.305054)
			(stroke
				(width 0.1)
				(type default)
			)
			(layer "F.Fab")
		)
		(fp_line
			(start -0.67945 -0.305054)
			(end -0.12065 -0.305054)
			(stroke
				(width 0.1)
				(type default)
			)
			(layer "F.Fab")
		)
		(pad "1" smd circle
			(at -0.40005 0 180)
			(size 0 0)
			(layers "F.Cu" "F.Mask" "F.Paste")
			(net "P3V3_AUX")
		)
		(pad "2" smd circle
			(at 0.40005 0 180)
			(size 0 0)
			(layers "F.Cu" "F.Mask" "F.Paste")
			(net "FM_P2E_BUF2_VODB_DB")
		)
	)
	(footprint ""
		(layer "F.Cu")
		(at 132.29082 -97.125028 90)
		(property "Reference" "R4404"
			(at 0 0 90)
			(layer "F.SilkS")
			(hide yes)
			(effects
				(font
					(size 1.27 1.27)
				)
			)
		)
		(property "Value" ""
			(at 0 0 90)
			(layer "F.Fab")
			(effects
				(font
					(size 1.27 1.27)
				)
			)
		)
		(duplicate_pad_numbers_are_jumpers no)
		(fp_line
			(start 0.7874 -0.4064)
			(end 0.7874 0.4064)
			(stroke
				(width 0.1524)
				(type default)
			)
			(layer "F.SilkS")
		)
		(fp_line
			(start -0.7874 -0.4064)
			(end 0.7874 -0.4064)
			(stroke
				(width 0.1524)
				(type default)
			)
			(layer "F.SilkS")
		)
		(fp_line
			(start 0.7874 0.4064)
			(end -0.7874 0.4064)
			(stroke
				(width 0.1524)
				(type default)
			)
			(layer "F.SilkS")
		)
		(fp_line
			(start -0.7874 0.4064)
			(end -0.7874 -0.4064)
			(stroke
				(width 0.1524)
				(type default)
			)
			(layer "F.SilkS")
		)
		(fp_line
			(start -0.12065 -0.305054)
			(end -0.12065 -0.2794)
			(stroke
				(width 0.1)
				(type default)
			)
			(layer "F.Fab")
		)
		(fp_line
			(start -0.67945 -0.305054)
			(end -0.12065 -0.305054)
			(stroke
				(width 0.1)
				(type default)
			)
			(layer "F.Fab")
		)
		(fp_line
			(start 0.67945 -0.3048)
			(end 0.67945 0.3048)
			(stroke
				(width 0.1)
				(type default)
			)
			(layer "F.Fab")
		)
		(fp_line
			(start 0.12065 -0.3048)
			(end 0.67945 -0.3048)
			(stroke
				(width 0.1)
				(type default)
			)
			(layer "F.Fab")
		)
		(fp_line
			(start 0.12065 -0.2794)
			(end 0.12065 -0.3048)
			(stroke
				(width 0.1)
				(type default)
			)
			(layer "F.Fab")
		)
		(fp_line
			(start -0.12065 -0.2794)
			(end 0.12065 -0.2794)
			(stroke
				(width 0.1)
				(type default)
			)
			(layer "F.Fab")
		)
		(fp_line
			(start 0.120396 0.2794)
			(end -0.12065 0.2794)
			(stroke
				(width 0.1)
				(type default)
			)
			(layer "F.Fab")
		)
		(fp_line
			(start -0.12065 0.2794)
			(end -0.12065 0.3048)
			(stroke
				(width 0.1)
				(type default)
			)
			(layer "F.Fab")
		)
		(fp_line
			(start 0.67945 0.3048)
			(end 0.120396 0.3048)
			(stroke
				(width 0.1)
				(type default)
			)
			(layer "F.Fab")
		)
		(fp_line
			(start 0.120396 0.3048)
			(end 0.120396 0.2794)
			(stroke
				(width 0.1)
				(type default)
			)
			(layer "F.Fab")
		)
		(fp_line
			(start -0.12065 0.3048)
			(end -0.67945 0.3048)
			(stroke
				(width 0.1)
				(type default)
			)
			(layer "F.Fab")
		)
		(fp_line
			(start -0.67945 0.3048)
			(end -0.67945 -0.305054)
			(stroke
				(width 0.1)
				(type default)
			)
			(layer "F.Fab")
		)
		(pad "1" smd circle
			(at -0.40005 0 90)
			(size 0 0)
			(layers "F.Cu" "F.Mask" "F.Paste")
			(net "H_CPU1_MEMHOT_OUT")
		)
		(pad "2" smd circle
			(at 0.40005 0 90)
			(size 0 0)
			(layers "F.Cu" "F.Mask" "F.Paste")
			(net "H_CPU1_MEMHOT_OUT_R")
		)
	)
	(footprint ""
		(layer "F.Cu")
		(at 236.015784 -391.837164 90)
		(property "Reference" "PD17"
			(at -2.8956 -3.343148 90)
			(unlocked yes)
			(layer "F.SilkS")
			(effects
				(font
					(size 0.7874 0.5842)
					(thickness 0.1524)
				)
			)
		)
		(property "Value" ""
			(at 0 0 90)
			(layer "F.Fab")
			(effects
				(font
					(size 1.27 1.27)
				)
			)
		)
		(duplicate_pad_numbers_are_jumpers no)
		(fp_line
			(start 3.541776 -2.54)
			(end 3.541776 2.54)
			(stroke
				(width 0.1524)
				(type default)
			)
			(layer "F.SilkS")
		)
		(fp_line
			(start -3.539744 -2.54)
			(end 3.541776 -2.54)
			(stroke
				(width 0.1524)
				(type default)
			)
			(layer "F.SilkS")
		)
		(fp_line
			(start 3.541776 2.54)
			(end -3.539744 2.54)
			(stroke
				(width 0.1524)
				(type default)
			)
			(layer "F.SilkS")
		)
		(fp_line
			(start -3.539744 2.54)
			(end -3.539744 -2.54)
			(stroke
				(width 0.1524)
				(type default)
			)
			(layer "F.SilkS")
		)
		(fp_poly
			(pts
				(xy -4.699 0.531876) (xy -4.699 1.547876) (xy -3.683 1.039876)
			)
			(stroke
				(width 0)
				(type default)
			)
			(fill yes)
			(layer "F.SilkS")
		)
		(fp_line
			(start 3.074924 -2.175002)
			(end 3.074924 2.175002)
			(stroke
				(width 0.1)
				(type default)
			)
			(layer "F.Fab")
		)
		(fp_line
			(start -3.074924 -2.175002)
			(end 3.074924 -2.175002)
			(stroke
				(width 0.1)
				(type default)
			)
			(layer "F.Fab")
		)
		(fp_line
			(start 3.074924 2.175002)
			(end -3.074924 2.175002)
			(stroke
				(width 0.1)
				(type default)
			)
			(layer "F.Fab")
		)
		(fp_line
			(start -3.074924 2.175002)
			(end -3.074924 -2.175002)
			(stroke
				(width 0.1)
				(type default)
			)
			(layer "F.Fab")
		)
		(fp_poly
			(pts
				(xy -4.699 0.531876) (xy -4.699 1.547876) (xy -3.683 1.039876)
			)
			(stroke
				(width 0)
				(type default)
			)
			(fill yes)
			(layer "F.Fab")
		)
		(pad "1" smd rect
			(at -2.765044 1.039876 270)
			(size 1.27 1.4224)
			(layers "F.Cu" "F.Mask" "F.Paste")
			(net "GND")
		)
		(pad "2" smd rect
			(at -2.765044 -1.039876 270)
			(size 1.27 1.4224)
			(layers "F.Cu" "F.Mask" "F.Paste")
			(net "GND")
		)
		(pad "K" smd rect
			(at 1.039876 0 270)
			(size 4.7244 4.8006)
			(layers "F.Cu" "F.Mask" "F.Paste")
			(net "P12V_AUX")
		)
	)
	(footprint ""
		(layer "F.Cu")
		(at 51.017678 -402.371052 -90)
		(property "Reference" "C712"
			(at 0 0 270)
			(layer "F.SilkS")
			(hide yes)
			(effects
				(font
					(size 1.27 1.27)
				)
			)
		)
		(property "Value" ""
			(at 0 0 270)
			(layer "F.Fab")
			(effects
				(font
					(size 1.27 1.27)
				)
			)
		)
		(duplicate_pad_numbers_are_jumpers no)
		(fp_line
			(start -0.299974 0.150114)
			(end -0.299974 -0.150114)
			(stroke
				(width 0.1)
				(type default)
			)
			(layer "F.Fab")
		)
		(fp_line
			(start 0.299974 0.150114)
			(end -0.299974 0.150114)
			(stroke
				(width 0.1)
				(type default)
			)
			(layer "F.Fab")
		)
		(fp_line
			(start -0.299974 -0.150114)
			(end 0.299974 -0.150114)
			(stroke
				(width 0.1)
				(type default)
			)
			(layer "F.Fab")
		)
		(fp_line
			(start 0.299974 -0.150114)
			(end 0.299974 0.150114)
			(stroke
				(width 0.1)
				(type default)
			)
			(layer "F.Fab")
		)
		(pad "1" smd rect
			(at -0.2667 0 270)
			(size 0.3048 0.381)
			(layers "F.Cu" "F.Mask" "F.Paste")
			(net "P5E_CPU1_PE0_TX_C_DN<14>")
		)
		(pad "2" smd rect
			(at 0.2667 0 270)
			(size 0.3048 0.381)
			(layers "F.Cu" "F.Mask" "F.Paste")
			(net "P5E_CPU1_PE0_TX_DN<14>")
		)
	)
	(footprint ""
		(layer "F.Cu")
		(at 372.871238 -361.704382 180)
		(property "Reference" "PC1249"
			(at 0 0 180)
			(layer "F.SilkS")
			(hide yes)
			(effects
				(font
					(size 1.27 1.27)
				)
			)
		)
		(property "Value" ""
			(at 0 0 180)
			(layer "F.Fab")
			(effects
				(font
					(size 1.27 1.27)
				)
			)
		)
		(duplicate_pad_numbers_are_jumpers no)
		(fp_line
			(start 0.7874 0.4064)
			(end -0.7874 0.4064)
			(stroke
				(width 0.1524)
				(type default)
			)
			(layer "F.SilkS")
		)
		(fp_line
			(start 0.7874 -0.4064)
			(end 0.7874 0.4064)
			(stroke
				(width 0.1524)
				(type default)
			)
			(layer "F.SilkS")
		)
		(fp_line
			(start -0.7874 0.4064)
			(end -0.7874 -0.4064)
			(stroke
				(width 0.1524)
				(type default)
			)
			(layer "F.SilkS")
		)
		(fp_line
			(start -0.7874 -0.4064)
			(end 0.7874 -0.4064)
			(stroke
				(width 0.1524)
				(type default)
			)
			(layer "F.SilkS")
		)
		(fp_line
			(start 0.67945 0.3048)
			(end 0.120396 0.3048)
			(stroke
				(width 0.1)
				(type default)
			)
			(layer "F.Fab")
		)
		(fp_line
			(start 0.67945 -0.3048)
			(end 0.67945 0.3048)
			(stroke
				(width 0.1)
				(type default)
			)
			(layer "F.Fab")
		)
		(fp_line
			(start 0.12065 -0.2794)
			(end 0.12065 -0.3048)
			(stroke
				(width 0.1)
				(type default)
			)
			(layer "F.Fab")
		)
		(fp_line
			(start 0.12065 -0.3048)
			(end 0.67945 -0.3048)
			(stroke
				(width 0.1)
				(type default)
			)
			(layer "F.Fab")
		)
		(fp_line
			(start 0.120396 0.3048)
			(end 0.120396 0.2794)
			(stroke
				(width 0.1)
				(type default)
			)
			(layer "F.Fab")
		)
		(fp_line
			(start 0.120396 0.2794)
			(end -0.12065 0.2794)
			(stroke
				(width 0.1)
				(type default)
			)
			(layer "F.Fab")
		)
		(fp_line
			(start -0.12065 0.3048)
			(end -0.67945 0.3048)
			(stroke
				(width 0.1)
				(type default)
			)
			(layer "F.Fab")
		)
		(fp_line
			(start -0.12065 0.2794)
			(end -0.12065 0.3048)
			(stroke
				(width 0.1)
				(type default)
			)
			(layer "F.Fab")
		)
		(fp_line
			(start -0.12065 -0.2794)
			(end 0.12065 -0.2794)
			(stroke
				(width 0.1)
				(type default)
			)
			(layer "F.Fab")
		)
		(fp_line
			(start -0.12065 -0.305054)
			(end -0.12065 -0.2794)
			(stroke
				(width 0.1)
				(type default)
			)
			(layer "F.Fab")
		)
		(fp_line
			(start -0.67945 0.3048)
			(end -0.67945 -0.305054)
			(stroke
				(width 0.1)
				(type default)
			)
			(layer "F.Fab")
		)
		(fp_line
			(start -0.67945 -0.305054)
			(end -0.12065 -0.305054)
			(stroke
				(width 0.1)
				(type default)
			)
			(layer "F.Fab")
		)
		(pad "1" smd circle
			(at -0.40005 0 180)
			(size 0 0)
			(layers "F.Cu" "F.Mask" "F.Paste")
			(net "SW_P12V_PVCCIN_CPU0_FLT")
		)
		(pad "2" smd circle
			(at 0.40005 0 180)
			(size 0 0)
			(layers "F.Cu" "F.Mask" "F.Paste")
			(net "GND")
		)
	)
)
